FILE_TYPE = CONNECTIVITY;
{Allegro Design Entry HDL 17.4-2019 S026 (4007227) 1/17/2022}
"PAGE_NUMBER" = 244;
0"NC";
1"GND\g";
2"GND\g";
3"GND\g";
4"GND\g";
5"GND\g";
6"P5V_AUX_VCC\G";
7"GND\g";
8"P5V_AUX_FB";
9"SW_P5V_AUX_FLT";
10"GND\g";
11"P5V_AUX_VCC\g";
12"GND\g";
13"PWRGD_P5V_AUX";
14"SW_P5V_AUX_SW";
15"MB0_P12V_STBY_PWRGD";
16"P5V_AUX_EN";
17"P5V_AUX_MODE";
18"P5V_AUX_CS";
19"P5V_AUX_REF";
20"SW_P5V_AUX_BST";
21"PWRGD_P5V_AUX_R";
22"P12V_AUX\g";
23"P5V_AUX\g";
24"GND\g";
25"GND\g";
%"GND"
"1","(-8200,8675)","0","pure_quanta_power","I1";
;
CDS_LIB"pure_quanta_power"
SIZE"1B"
HDL_POWER"GND";
"A<SIZE-1..0>\NAC"1;
%"Q_CAP"
"1","(-7025,8900)","0","pure_quanta","I10";
;
LOCATION"PC1850"
$SEC"1"
CDS_SEC"1"
VALUE"22UF"
TOLERANCE"20%"
VOLTAGE"16V"
MATERIAL"X6S"
PACK_TYPE"C0805"
CDS_LIB"pure_quanta"
PART_NUMBER"CH6223MEA01";
"B"
$PN"2"10;
"A"
$PN"1"9;
%"Q_CAP"
"1","(-6575,8900)","0","pure_quanta","I11";
;
LOCATION"PC1898"
$SEC"1"
CDS_SEC"1"
MATERIAL"X6S"
PACK_TYPE"C0805"
TOLERANCE"20%"
VALUE"22UF"
VOLTAGE"16V"
CDS_LIB"pure_quanta"
PART_NUMBER"CH6223MEA01";
"B"
$PN"2"10;
"A"
$PN"1"9;
%"Q_CAP"
"1","(-6175,8900)","0","pure_quanta","I13";
;
LOCATION"PC1846"
$SEC"1"
CDS_SEC"1"
VALUE"1UF"
VOLTAGE"16V"
TOLERANCE"10%"
MATERIAL"X6S"
PACK_TYPE"C0402"
CDS_LIB"pure_quanta"
PART_NUMBER"CH5103KEB01";
"B"
$PN"2"10;
"A"
$PN"1"9;
%"GND"
"1","(-5887,6443)","0","pure_quanta_power","I14";
;
SIZE"1B"
CDS_LIB"pure_quanta_power"
HDL_POWER"GND";
"A<SIZE-1..0>\NAC"2;
%"Q_RES"
"2","(-5887,6732)","0","pure_quanta","I15";
;
LOCATION"PR8089"
SEC"1"
MATERIAL"CHIP"
PACK_TYPE"0402LF"
TOLERANCE"1%"
WATTAGE"1/16W"
VALUE"16.9K"
SEC_TYPE"0402LF"
CDS_LIB"pure_quanta"
PART_NUMBER"CS31692FB03";
"A"
$PN"1"18;
"B"
$PN"2"2;
%"GND"
"1","(-4375,6625)","0","pure_quanta_power","I16";
;
SIZE"1B"
CDS_LIB"pure_quanta_power"
HDL_POWER"GND";
"A<SIZE-1..0>\NAC"12;
%"GND"
"1","(-4250,6625)","0","pure_quanta_power","I17";
;
SIZE"1B"
CDS_LIB"pure_quanta_power"
HDL_POWER"GND";
"A<SIZE-1..0>\NAC"3;
%"GND"
"1","(-5575,7375)","0","pure_quanta_power","I18";
;
CDS_LIB"pure_quanta_power"
SIZE"1B"
HDL_POWER"GND";
"A<SIZE-1..0>\NAC"4;
%"Q_CAP"
"1","(-4250,6850)","0","pure_quanta","I19";
;
LOCATION"PC1853"
$SEC"1"
CDS_SEC"1"
PACK_TYPE"0402"
MATERIAL"X7R"
TOLERANCE"10%"
VOLTAGE"25V"
VALUE"0.1UF"
CDS_LIB"pure_quanta"
PART_NUMBER"CH4104K1B00";
"B"
$PN"2"3;
"A"
$PN"1"19;
%"Q_CAP"
"1","(-8200,8925)","0","pure_quanta","I2";
;
LOCATION"PC1648"
$SEC"1"
CDS_SEC"1"
MATERIAL"X6S"
TOLERANCE"10%"
VOLTAGE"25V"
VALUE"0.1UF"
PACK_TYPE"C0402"
CDS_LIB"pure_quanta"
PART_NUMBER"CH4104KEB00";
"B"
$PN"2"1;
"A"
$PN"1"22;
%"Q_CAP"
"2","(-2325,6625)","0","pure_quanta","I20";
;
LOCATION"PC1877"
$SEC"1"
CDS_SEC"1"
MATERIAL"NPO"
TOLERANCE"5%"
PACK_TYPE"0402"
VOLTAGE"50V"
VALUE"47PF"
CDS_LIB"pure_quanta"
PART_NUMBER"TMP_QCH04706JB01";
"A"
$PN"1"8;
"B"
$PN"2"23;
%"GND"
"1","(-3825,6700)","0","pure_quanta_power","I21";
;
SIZE"1B"
CDS_LIB"pure_quanta_power"
HDL_POWER"GND";
"A<SIZE-1..0>\NAC"25;
%"GND"
"1","(-3675,6700)","0","pure_quanta_power","I22";
;
SIZE"1B"
CDS_LIB"pure_quanta_power"
HDL_POWER"GND";
"A<SIZE-1..0>\NAC"5;
%"Q_RES"
"2","(-3675,7025)","0","pure_quanta","I23";
;
LOCATION"PR8091"
$SEC"1"
CDS_SEC"1"
PACK_TYPE"0402LF"
TOLERANCE"0.1%"
VALUE"11.8K"
MATERIAL"CHIP"
WATTAGE"1/16W"
CDS_LIB"pure_quanta"
PART_NUMBER"CS31182BB06";
"A"
$PN"1"8;
"B"
$PN"2"5;
%"Q_CAP"
"1","(-3725,7900)","0","pure_quanta","I24";
;
LOCATION"PC1847"
$SEC"1"
CDS_SEC"1"
VALUE"0.22UF"
TOLERANCE"10%"
MATERIAL"X7R"
PACK_TYPE"C0402"
VOLTAGE"25V"
CDS_LIB"pure_quanta"
PART_NUMBER"CH4224K1B01";
"B"
$PN"2"14;
"A"
$PN"1"20;
%"Q_RES"
"2","(-3725,8625)","0","pure_quanta","I25";
;
LOCATION"R2356"
SEC"1"
PACK_TYPE"0402LF"
TOLERANCE"1%"
MATERIAL"CHIP"
WATTAGE"1/16W"
VALUE"10K"
CDS_LIB"pure_quanta"
SEC_TYPE"0402LF"
PART_NUMBER"CS31002FB08";
"A"
$PN"1"6;
"B"
$PN"2"21;
%"Q_RES"
"1","(-3150,8250)","0","pure_quanta","I26";
;
LOCATION"R2316"
$SEC"1"
CDS_SEC"1"
WATTAGE"1/16W"
VALUE"0"
MATERIAL"CHIP"
PACK_TYPE"0402LF"
TOLERANCE"5%"
CDS_LIB"pure_quanta"
PART_NUMBER"CS00002JB13";
"B"
$PN"2"13;
"A"
$PN"1"21;
%"Q_RES"
"1","(-2300,6950)","0","pure_quanta","I27";
;
LOCATION"PR8092"
$SEC"1"
CDS_SEC"1"
TOLERANCE"1%"
MATERIAL"CHIP"
VALUE"86.6K"
PACK_TYPE"0402LF"
WATTAGE"1/16W"
CDS_LIB"pure_quanta"
PART_NUMBER"CS38662FB05";
"B"
$PN"2"23;
"A"
$PN"1"8;
%"Q_INDUCTOR"
"1","(-2825,7775)","0","pure_quanta","I28";
;
LOCATION"PL8065"
$SEC"1"
CDS_SEC"1"
PACK_TYPE"SMLF"
MATERIAL"IND"
VALUE"4.7UH"
CDS_LIB"pure_quanta"
NEEDS_NO_SIZE"TRUE"
PART_NUMBER"CV-47A0MZ10";
"1"
$PN"1"14;
"2"
$PN"2"23;
%"P1V0_AUX"
"1","(-8196,9345)","0","pure_quanta_power","I3";
;
HDL_POWER"P12V_AUX"
CDS_LIB"pure_quanta_power";
"A"22;
%"Q_CAPP"
"1","(-1550,7500)","0","pure_quanta","I30";
;
LOCATION"PC1845"
$SEC"1"
CDS_SEC"1"
VALUE"220UF"
PACK_TYPE"SMLF"
VOLTAGE"6.3V"
TOLERANCE"20%"
MATERIAL"ALUM"
CDS_LIB"pure_quanta"
PART_NUMBER"CC72201MZ28";
"A"
$PN"1"23;
"B"
$PN"2"24;
%"Q_CAP"
"1","(-1100,7500)","0","pure_quanta","I31";
;
LOCATION"PC1855"
$SEC"1"
CDS_SEC"1"
MATERIAL"X6S"
VOLTAGE"10V"
TOLERANCE"20%"
PACK_TYPE"C0805"
VALUE"22UF"
CDS_LIB"pure_quanta"
PART_NUMBER"CH6222MEA01";
"B"
$PN"2"24;
"A"
$PN"1"23;
%"Q_CAP"
"1","(-600,7500)","0","pure_quanta","I32";
;
LOCATION"PC1856"
$SEC"1"
CDS_SEC"1"
TOLERANCE"20%"
VOLTAGE"10V"
VALUE"22UF"
PACK_TYPE"C0805"
MATERIAL"X6S"
CDS_LIB"pure_quanta"
PART_NUMBER"CH6222MEA01";
"B"
$PN"2"24;
"A"
$PN"1"23;
%"GND"
"1","(-175,7100)","0","pure_quanta_power","I33";
;
SIZE"1B"
CDS_LIB"pure_quanta_power"
HDL_POWER"GND";
"A<SIZE-1..0>\NAC"24;
%"Q_CAP"
"1","(-175,7500)","0","pure_quanta","I34";
;
LOCATION"PC1852"
SEC"1"
VOLTAGE"25V"
VALUE"0.1UF"
TOLERANCE"10%"
MATERIAL"X7R"
PACK_TYPE"0402"
SEC_TYPE"0402"
CDS_LIB"pure_quanta"
PART_NUMBER"CH4104K1B00";
"B"
$PN"2"24;
"A"
$PN"1"23;
%"UNIVERSAL_POWER"
"1","(-3725,8925)","0","pure_quanta_power","I35";
;
HDL_POWER"P5V_AUX_VCC"
CDS_LIB"pure_quanta_power";
"A"6;
%"P1V0"
"1","(325,8225)","0","pure_quanta_power","I36";
;
HDL_POWER"P5V_AUX"
CDS_LIB"pure_quanta_power";
"A"23;
%"Q_RES"
"1","(-5975,7450)","0","pure_quanta","I37";
;
LOCATION"PR3337"
$SEC"1"
CDS_SEC"1"
VALUE"0"
WATTAGE"1/16W"
PACK_TYPE"0402LF"
TOLERANCE"5%"
MATERIAL"CHIP"
CDS_LIB"pure_quanta"
PART_NUMBER"CS00002JB13";
"B"
$PN"2"4;
"A"
$PN"1"17;
%"MPQ8633AGLEC807Z"
"1","(-5000,7575)","0","pure_quanta","I38";
;
LOCATION"U326"
$SEC"1"
CDS_SEC"1"
PART_TYPE"SMLF"
MATERIAL"IC"
VALUE"MPQ8633AGLE-C807-Z"
NEEDS_NO_SIZE"TRUE"
CDS_LMAN_SYM_OUTLINE"-250,725,250,-725"
CDS_LIB"pure_quanta"
PART_NUMBER"AL008633007";
"VIN2"
$PN"21"9;
"CS"
$PN"3"18;
"MODE"
$PN"4"17;
"TRK_REF"
$PN"5"19;
"SW"
$PN"20"14;
"RGND"
$PN"6"25;
"VCC"
$PN"19"11;
"AGND"
$PN"2"12;
"FB"
$PN"7"8;
"BST"
$PN"1"20;
"EN"
$PN"8"16;
"PGND"
$PN"11_18"12;
"PGOOD"
$PN"9"21;
"VIN1"
$PN"10"9;
%"GND"
"1","(-6825,6650)","0","pure_quanta_power","I4";
;
CDS_LIB"pure_quanta_power"
SIZE"1B"
HDL_POWER"GND";
"A<SIZE-1..0>\NAC"7;
%"Q_RES"
"1","(-6250,7750)","0","pure_quanta","I40";
;
LOCATION"R6097"
$SEC"1"
CDS_SEC"1"
MATERIAL"CHIP"
VALUE"0"
WATTAGE"1/16W"
TOLERANCE"5%"
PACK_TYPE"0402LF"
CDS_LIB"pure_quanta"
PART_NUMBER"CS00002JB13";
"B"
$PN"2"16;
"A"
$PN"1"15;
%"Q_INDUCTOR"
"1","(-7925,9150)","0","pure_quanta","I5";
;
LOCATION"PL8064"
$SEC"1"
CDS_SEC"1"
PACK_TYPE"SMLF"
VALUE"BLM18SN220TN1D/8000MA"
MATERIAL"IND"
NEEDS_NO_SIZE"TRUE"
CDS_LIB"pure_quanta"
PART_NUMBER"CX220TN1001";
"1"
$PN"1"22;
"2"
$PN"2"9;
%"GND"
"1","(-7425,8525)","0","pure_quanta_power","I6";
;
CDS_LIB"pure_quanta_power"
SIZE"1B"
HDL_POWER"GND";
"A<SIZE-1..0>\NAC"10;
%"Q_CAP"
"1","(-7425,8900)","0","pure_quanta","I7";
;
LOCATION"PC1849"
$SEC"1"
CDS_SEC"1"
VALUE"22UF"
PACK_TYPE"C0805"
VOLTAGE"16V"
TOLERANCE"20%"
MATERIAL"X6S"
CDS_LIB"pure_quanta"
PART_NUMBER"CH6223MEA01";
"B"
$PN"2"10;
"A"
$PN"1"9;
%"Q_CAP"
"1","(-6825,7025)","2","pure_quanta","I8";
;
LOCATION"PC1848"
SEC"1"
VALUE"1UF"
TOLERANCE"10%"
MATERIAL"X6S"
PACK_TYPE"C0402"
VOLTAGE"25V"
CDS_LIB"pure_quanta"
SIGNAL_MODEL"DEFAULT_CAPACITOR_100000PF_2_1"
SEC_TYPE"C0402"
PART_NUMBER"CH5104KEB02";
"B"
$PN"2"7;
"A"
$PN"1"11;
%"UNIVERSAL_POWER"
"1","(-6825,7525)","0","pure_quanta_power","I9";
;
HDL_POWER"P5V_AUX_VCC"
CDS_LIB"pure_quanta_power";
"A"11;
END.
